(kicad_pcb
	(version 20241229)
	(generator "pcbnew")
	(generator_version "9.0")
	(general
		(thickness 1.6)
		(legacy_teardrops no)
	)
	(paper "A4")
	(title_block
		(title "GMSL Deserializer")
		(date "2025-10-09")
		(rev "1.0.4")
		(company "Antmicro Ltd")
		(comment 1 "www.antmicro.com")
		(comment 9 "footprints 160-164 of 235")
	)
	(layers
		(0 "F.Cu" signal)
		(4 "In1.Cu" power)
		(6 "In2.Cu" power)
		(2 "B.Cu" signal)
		(9 "F.Adhes" user "F.Adhesive")
		(11 "B.Adhes" user "B.Adhesive")
		(13 "F.Paste" user)
		(15 "B.Paste" user)
		(5 "F.SilkS" user "F.Silkscreen")
		(7 "B.SilkS" user "B.Silkscreen")
		(1 "F.Mask" user)
		(3 "B.Mask" user)
		(17 "Dwgs.User" user "User.Drawings")
		(19 "Cmts.User" user "User.Comments")
		(21 "Eco1.User" user "User.Eco1")
		(23 "Eco2.User" user "User.Eco2")
		(25 "Edge.Cuts" user)
		(27 "Margin" user)
		(31 "F.CrtYd" user "F.Courtyard")
		(29 "B.CrtYd" user "B.Courtyard")
		(35 "F.Fab" user)
		(33 "B.Fab" user)
	)
	(footprint "antmicro-footprints:SOT-23-5"
		(layer "F.Cu")
		(at 128.198 75.034 90)
		(property "Reference" "U3"
			(at -0.531 -1.96 90)
			(layer "F.SilkS")
			(effects
				(font
					(size 0.7 0.7)
					(thickness 0.15)
				)
				(justify right bottom)
			)
		)
		(property "Value" "LMR62014XMF"
			(at 0.002 2.799 90)
			(layer "F.Fab")
			(effects
				(font
					(size 0.7 0.7)
					(thickness 0.15)
				)
				(justify left bottom)
			)
		)
		(property "Datasheet" "https://www.ti.com/lit/ds/symlink/lmr62014.pdf?ts=1698148381034"
			(at 0 0 90)
			(layer "F.Fab")
			(hide yes)
			(effects
				(font
					(size 1.27 1.27)
					(thickness 0.15)
				)
			)
		)
		(property "Description" "Step-Up Regulator  2.7V to 14V, 1.4A"
			(at 0 0 90)
			(layer "F.Fab")
			(hide yes)
			(effects
				(font
					(size 1.27 1.27)
					(thickness 0.15)
				)
			)
		)
		(property "Author" "Antmicro"
			(at 203.232 -53.164 0)
			(layer "F.Fab")
			(hide yes)
			(effects
				(font
					(size 1 1)
					(thickness 0.15)
				)
			)
		)
		(property "License" "Apache-2.0"
			(at 203.232 -53.164 0)
			(layer "F.Fab")
			(hide yes)
			(effects
				(font
					(size 1 1)
					(thickness 0.15)
				)
			)
		)
		(property "MPN" "LMR62014XMF/NOPB"
			(at 203.232 -53.164 0)
			(layer "F.Fab")
			(hide yes)
			(effects
				(font
					(size 1 1)
					(thickness 0.15)
				)
			)
		)
		(property "Manufacturer" "Texas Instruments"
			(at 203.232 -53.164 0)
			(layer "F.Fab")
			(hide yes)
			(effects
				(font
					(size 1 1)
					(thickness 0.15)
				)
			)
		)
		(sheetname "/Power/")
		(sheetfile "power.kicad_sch")
		(attr smd)
		(fp_line
			(start 0.8 -1.6)
			(end 0.5 -1.6)
			(stroke
				(width 0.15)
				(type solid)
			)
			(layer "F.SilkS")
		)
		(fp_line
			(start -0.8 -1.6)
			(end -0.5 -1.6)
			(stroke
				(width 0.15)
				(type solid)
			)
			(layer "F.SilkS")
		)
		(fp_line
			(start -0.8 -1.6)
			(end -0.8 -1.3)
			(stroke
				(width 0.15)
				(type solid)
			)
			(layer "F.SilkS")
		)
		(fp_line
			(start 0.8 -1.3)
			(end 0.8 -1.6)
			(stroke
				(width 0.15)
				(type solid)
			)
			(layer "F.SilkS")
		)
		(fp_line
			(start 0.8 0.55)
			(end 0.8 -0.55)
			(stroke
				(width 0.15)
				(type solid)
			)
			(layer "F.SilkS")
		)
		(fp_line
			(start 0.8 1.3)
			(end 0.8 1.599)
			(stroke
				(width 0.15)
				(type solid)
			)
			(layer "F.SilkS")
		)
		(fp_line
			(start 0.8 1.599)
			(end 0.549 1.599)
			(stroke
				(width 0.15)
				(type solid)
			)
			(layer "F.SilkS")
		)
		(fp_line
			(start -0.55 1.6)
			(end -0.85 1.6)
			(stroke
				(width 0.15)
				(type solid)
			)
			(layer "F.SilkS")
		)
		(fp_line
			(start -0.85 1.6)
			(end -0.85 1.301)
			(stroke
				(width 0.15)
				(type solid)
			)
			(layer "F.SilkS")
		)
		(fp_circle
			(center -1.25 -1.5)
			(end -1.2 -1.5)
			(stroke
				(width 0.15)
				(type solid)
			)
			(fill yes)
			(layer "F.SilkS")
		)
		(fp_rect
			(start 1.9 -1.76)
			(end -1.9 1.75)
			(stroke
				(width 0.05)
				(type solid)
			)
			(fill no)
			(layer "F.CrtYd")
		)
		(fp_line
			(start -0.398 -1.526)
			(end -0.874 -1.05)
			(stroke
				(width 0.15)
				(type solid)
			)
			(layer "F.Fab")
		)
		(fp_rect
			(start 0.874 1.523)
			(end -0.873 -1.525)
			(stroke
				(width 0.15)
				(type solid)
			)
			(fill no)
			(layer "F.Fab")
		)
		(pad "1" smd rect
			(at -1.351 -0.951)
			(size 0.55 1)
			(layers "F.Cu" "F.Mask" "F.Paste")
			(net 124 "/Power/SW_12V")
			(pinfunction "SW")
			(pintype "power_out")
		)
		(pad "2" smd rect
			(at -1.351 0)
			(size 0.55 1)
			(layers "F.Cu" "F.Mask" "F.Paste")
			(net 1 "GND")
			(pinfunction "GND")
			(pintype "power_in")
		)
		(pad "3" smd rect
			(at -1.351 0.949)
			(size 0.55 1)
			(layers "F.Cu" "F.Mask" "F.Paste")
			(net 122 "/Power/FB_12V")
			(pinfunction "FB")
			(pintype "input")
		)
		(pad "4" smd rect
			(at 1.35 0.949)
			(size 0.55 1)
			(layers "F.Cu" "F.Mask" "F.Paste")
			(net 125 "/Power/EN_12V")
			(pinfunction "~{SHDN}")
			(pintype "input")
		)
		(pad "5" smd rect
			(at 1.35 -0.951)
			(size 0.55 1)
			(layers "F.Cu" "F.Mask" "F.Paste")
			(net 5 "+5V")
			(pinfunction "VIN")
			(pintype "power_in")
		)
	)
	(footprint "antmicro-footprints:LED_0603_1608Metric_G"
		(layer "F.Cu")
		(at 147.85 96.1 -90)
		(descr "LED SMD 0603 Green")
		(tags "LED SMD 0603 Green")
		(property "Reference" "D18"
			(at -4.488889 29.433333 0)
			(layer "F.SilkS")
			(effects
				(font
					(size 0.7 0.7)
					(thickness 0.15)
				)
				(justify right bottom)
			)
		)
		(property "Value" "LED_G_0603_LTST-C190GKT"
			(at -0.001 1.599 90)
			(layer "F.Fab")
			(effects
				(font
					(size 0.7 0.7)
					(thickness 0.15)
				)
				(justify right bottom)
			)
		)
		(property "Datasheet" "https://media.digikey.com/pdf/Data%20Sheets/Lite-On%20PDFs/LTST-C190GKT.pdf"
			(at 0 0 270)
			(layer "F.Fab")
			(hide yes)
			(effects
				(font
					(size 1.27 1.27)
					(thickness 0.15)
				)
			)
		)
		(property "Description" "LED, Green, SMD, 0603, 20 mA, 2.1 V, 569 nm"
			(at 0 0 270)
			(layer "F.Fab")
			(hide yes)
			(effects
				(font
					(size 1.27 1.27)
					(thickness 0.15)
				)
			)
		)
		(property "Author" "Antmicro"
			(at 51.75 243.95 0)
			(layer "F.Fab")
			(hide yes)
			(effects
				(font
					(size 1 1)
					(thickness 0.15)
				)
			)
		)
		(property "Color" "Green"
			(at 51.75 243.95 0)
			(layer "F.Fab")
			(hide yes)
			(effects
				(font
					(size 1 1)
					(thickness 0.15)
				)
			)
		)
		(property "License" "Apache-2.0"
			(at 51.75 243.95 0)
			(layer "F.Fab")
			(hide yes)
			(effects
				(font
					(size 1 1)
					(thickness 0.15)
				)
			)
		)
		(property "MPN" "LTST-C190GKT"
			(at 51.75 243.95 0)
			(layer "F.Fab")
			(hide yes)
			(effects
				(font
					(size 1 1)
					(thickness 0.15)
				)
			)
		)
		(property "Manufacturer" "Lite-On"
			(at 51.75 243.95 0)
			(layer "F.Fab")
			(hide yes)
			(effects
				(font
					(size 1 1)
					(thickness 0.15)
				)
			)
		)
		(property "VSD_class" "LED"
			(at 51.75 243.95 0)
			(layer "F.Fab")
			(hide yes)
			(effects
				(font
					(size 1 1)
					(thickness 0.15)
				)
			)
		)
		(sheetname "/Power/")
		(sheetfile "power.kicad_sch")
		(attr smd)
		(fp_line
			(start 0.22 0.35)
			(end -0.22 0.35)
			(stroke
				(width 0.15)
				(type solid)
			)
			(layer "F.SilkS")
		)
		(fp_line
			(start -0.094672 0.201008)
			(end -0.094672 -0.198992)
			(stroke
				(width 0.1)
				(type solid)
			)
			(layer "F.SilkS")
		)
		(fp_line
			(start 0.105328 0.201008)
			(end -0.094672 0.001008)
			(stroke
				(width 0.1)
				(type solid)
			)
			(layer "F.SilkS")
		)
		(fp_line
			(start 0.105328 0.201008)
			(end 0.105328 -0.198992)
			(stroke
				(width 0.1)
				(type solid)
			)
			(layer "F.SilkS")
		)
		(fp_line
			(start -0.094672 0.001008)
			(end -0.24 0.001008)
			(stroke
				(width 0.1)
				(type solid)
			)
			(layer "F.SilkS")
		)
		(fp_line
			(start -0.094672 0.001008)
			(end 0.105328 -0.198992)
			(stroke
				(width 0.1)
				(type solid)
			)
			(layer "F.SilkS")
		)
		(fp_line
			(start 0.105328 0.001008)
			(end 0.24 0.001)
			(stroke
				(width 0.1)
				(type solid)
			)
			(layer "F.SilkS")
		)
		(fp_line
			(start -1.18 -0.319)
			(end -1.18 0.321)
			(stroke
				(width 0.15)
				(type solid)
			)
			(layer "F.SilkS")
		)
		(fp_line
			(start 0.22 -0.35)
			(end -0.22 -0.35)
			(stroke
				(width 0.15)
				(type solid)
			)
			(layer "F.SilkS")
		)
		(fp_rect
			(start 1.25 0.65)
			(end -1.25 -0.65)
			(stroke
				(width 0.05)
				(type solid)
			)
			(fill no)
			(layer "F.CrtYd")
		)
		(fp_line
			(start -0.199 0.2)
			(end -0.199 0.1)
			(stroke
				(width 0.15)
				(type solid)
			)
			(layer "F.Fab")
		)
		(fp_line
			(start 0.201 0.2)
			(end 0.201 0)
			(stroke
				(width 0.15)
				(type solid)
			)
			(layer "F.Fab")
		)
		(fp_line
			(start -0.199 0)
			(end -0.597 0)
			(stroke
				(width 0.15)
				(type solid)
			)
			(layer "F.Fab")
		)
		(fp_line
			(start -0.101 0)
			(end 0.201 0.2)
			(stroke
				(width 0.15)
				(type solid)
			)
			(layer "F.Fab")
		)
		(fp_line
			(start 0.201 0)
			(end 0.201 -0.202)
			(stroke
				(width 0.15)
				(type solid)
			)
			(layer "F.Fab")
		)
		(fp_line
			(start 0.599 0)
			(end 0.201 0)
			(stroke
				(width 0.15)
				(type solid)
			)
			(layer "F.Fab")
		)
		(fp_line
			(start -0.199 -0.202)
			(end -0.199 0.1)
			(stroke
				(width 0.15)
				(type solid)
			)
			(layer "F.Fab")
		)
		(fp_line
			(start 0.201 -0.202)
			(end -0.101 0)
			(stroke
				(width 0.15)
				(type solid)
			)
			(layer "F.Fab")
		)
		(fp_rect
			(start 0.848 0.4)
			(end -0.85 -0.402)
			(stroke
				(width 0.15)
				(type solid)
			)
			(fill no)
			(layer "F.Fab")
		)
		(pad "1" smd roundrect
			(at -0.7 0 90)
			(size 0.8 1)
			(layers "F.Cu" "F.Mask" "F.Paste")
			(roundrect_rratio 0.2)
			(net 142 "Net-(D18-C)")
			(pinfunction "C")
			(pintype "passive")
		)
		(pad "2" smd roundrect
			(at 0.7 0 90)
			(size 0.8 1)
			(layers "F.Cu" "F.Mask" "F.Paste")
			(roundrect_rratio 0.2)
			(net 123 "/Power/OUT_12V")
			(pinfunction "A")
			(pintype "passive")
		)
	)
	(footprint "antmicro-footprints:C_0603_1608Metric"
		(layer "F.Cu")
		(at 129.448 78.844 -90)
		(descr "Capacitor SMD 0603")
		(tags "capacitor 0603")
		(property "Reference" "C16"
			(at -0.612 0.759 90)
			(layer "F.SilkS")
			(effects
				(font
					(size 0.7 0.7)
					(thickness 0.15)
				)
				(justify right bottom)
			)
		)
		(property "Value" "C_10u_25V_0603"
			(at -2.44357 2.792288 90)
			(layer "F.Fab")
			(effects
				(font
					(size 0.7 0.7)
					(thickness 0.15)
				)
				(justify right bottom)
			)
		)
		(property "Datasheet" "https://product.tdk.com/en/search/capacitor/ceramic/mlcc/info?part_no=C1608X5R1E106M080AC"
			(at 0 0 270)
			(layer "F.Fab")
			(hide yes)
			(effects
				(font
					(size 1.27 1.27)
					(thickness 0.15)
				)
			)
		)
		(property "Description" "SMD Multilayer Ceramic Capacitor, 10 µF, 25 V, 0603 [1608 Metric], ± 20%, X5R, C"
			(at 0 0 270)
			(layer "F.Fab")
			(hide yes)
			(effects
				(font
					(size 1.27 1.27)
					(thickness 0.15)
				)
			)
		)
		(property "Author" "Antmicro"
			(at 50.604 208.292 0)
			(layer "F.Fab")
			(hide yes)
			(effects
				(font
					(size 1 1)
					(thickness 0.15)
				)
			)
		)
		(property "Dielectric" ""
			(at 50.604 208.292 0)
			(layer "F.Fab")
			(hide yes)
			(effects
				(font
					(size 1 1)
					(thickness 0.15)
				)
			)
		)
		(property "License" "Apache-2.0"
			(at 50.604 208.292 0)
			(layer "F.Fab")
			(hide yes)
			(effects
				(font
					(size 1 1)
					(thickness 0.15)
				)
			)
		)
		(property "MPN" "C1608X5R1E106M080AC"
			(at 50.604 208.292 0)
			(layer "F.Fab")
			(hide yes)
			(effects
				(font
					(size 1 1)
					(thickness 0.15)
				)
			)
		)
		(property "Manufacturer" "TDK"
			(at 50.604 208.292 0)
			(layer "F.Fab")
			(hide yes)
			(effects
				(font
					(size 1 1)
					(thickness 0.15)
				)
			)
		)
		(property "Val" "10u"
			(at 50.604 208.292 0)
			(layer "F.Fab")
			(hide yes)
			(effects
				(font
					(size 1 1)
					(thickness 0.15)
				)
			)
		)
		(property "Voltage" "25V"
			(at 50.604 208.292 0)
			(layer "F.Fab")
			(hide yes)
			(effects
				(font
					(size 1 1)
					(thickness 0.15)
				)
			)
		)
		(sheetname "/Power/")
		(sheetfile "power.kicad_sch")
		(attr smd)
		(fp_line
			(start -0.15 0.4)
			(end 0.15 0.4)
			(stroke
				(width 0.15)
				(type solid)
			)
			(layer "F.SilkS")
		)
		(fp_line
			(start -0.15 -0.4)
			(end 0.15 -0.4)
			(stroke
				(width 0.15)
				(type solid)
			)
			(layer "F.SilkS")
		)
		(fp_rect
			(start -1.25 -0.65)
			(end 1.25 0.65)
			(stroke
				(width 0.05)
				(type solid)
			)
			(fill no)
			(layer "F.CrtYd")
		)
		(fp_rect
			(start -0.8 -0.4)
			(end 0.8 0.4)
			(stroke
				(width 0.15)
				(type solid)
			)
			(fill no)
			(layer "F.Fab")
		)
		(pad "1" smd roundrect
			(at -0.7 0 270)
			(size 0.8 1)
			(layers "F.Cu" "F.Mask" "F.Paste")
			(roundrect_rratio 0.2)
			(net 1 "GND")
			(pintype "passive")
		)
		(pad "2" smd roundrect
			(at 0.7 0 270)
			(size 0.8 1)
			(layers "F.Cu" "F.Mask" "F.Paste")
			(roundrect_rratio 0.2)
			(net 123 "/Power/OUT_12V")
			(pintype "passive")
		)
	)
	(footprint "antmicro-footprints:C_0402_1005Metric"
		(layer "F.Cu")
		(at 142.113 74.295 135)
		(descr "Capacitor SMD 0402")
		(tags "capacitor SMD 0402")
		(property "Reference" "C28"
			(at 6.272037 -0.486489 315)
			(unlocked yes)
			(layer "F.SilkS")
			(effects
				(font
					(size 0.7 0.7)
					(thickness 0.15)
				)
				(justify left bottom)
			)
		)
		(property "Value" "C_100n_0402"
			(at -1.022927 2.155213 135)
			(layer "F.Fab")
			(effects
				(font
					(size 0.7 0.7)
					(thickness 0.15)
				)
				(justify left bottom)
			)
		)
		(property "Datasheet" "https://www.murata.com/products/productdetail?partno=GRM155R61H104KE14%23"
			(at 0 0 135)
			(layer "F.Fab")
			(hide yes)
			(effects
				(font
					(size 1.27 1.27)
					(thickness 0.15)
				)
			)
		)
		(property "Description" "SMD Multilayer Ceramic Capacitor, 0.1 µF, 50 V, 0402 [1005 Metric], ± 10%, X5R, GRM Series"
			(at 0 0 135)
			(layer "F.Fab")
			(hide yes)
			(effects
				(font
					(size 1.27 1.27)
					(thickness 0.15)
				)
			)
		)
		(property "Author" "Antmicro"
			(at 295.136564 26.340432 0)
			(layer "F.Fab")
			(hide yes)
			(effects
				(font
					(size 1 1)
					(thickness 0.15)
				)
			)
		)
		(property "Dielectric" "X5R"
			(at 295.136564 26.340432 0)
			(layer "F.Fab")
			(hide yes)
			(effects
				(font
					(size 1 1)
					(thickness 0.15)
				)
			)
		)
		(property "License" "Apache-2.0"
			(at 295.136564 26.340432 0)
			(layer "F.Fab")
			(hide yes)
			(effects
				(font
					(size 1 1)
					(thickness 0.15)
				)
			)
		)
		(property "MPN" "GRM155R61H104KE14D"
			(at 295.136564 26.340432 0)
			(layer "F.Fab")
			(hide yes)
			(effects
				(font
					(size 1 1)
					(thickness 0.15)
				)
			)
		)
		(property "Manufacturer" "Murata"
			(at 295.136564 26.340432 0)
			(layer "F.Fab")
			(hide yes)
			(effects
				(font
					(size 1 1)
					(thickness 0.15)
				)
			)
		)
		(property "Val" "100n"
			(at 295.136564 26.340432 0)
			(layer "F.Fab")
			(hide yes)
			(effects
				(font
					(size 1 1)
					(thickness 0.15)
				)
			)
		)
		(property "Voltage" "50V"
			(at 295.136564 26.340432 0)
			(layer "F.Fab")
			(hide yes)
			(effects
				(font
					(size 1 1)
					(thickness 0.15)
				)
			)
		)
		(sheetname "/Deserializer/")
		(sheetfile "deserializer.kicad_sch")
		(attr smd)
		(fp_poly
			(pts
				(xy -0.925 -0.47) (xy 0.925 -0.47) (xy 0.925 0.47) (xy -0.925 0.47)
			)
			(stroke
				(width 0.05)
				(type default)
			)
			(fill no)
			(layer "F.CrtYd")
		)
		(fp_line
			(start 0.504 -0.25)
			(end 0.504 0.248)
			(stroke
				(width 0.15)
				(type solid)
			)
			(layer "F.Fab")
		)
		(fp_line
			(start 0.504 0.248)
			(end -0.494 0.248)
			(stroke
				(width 0.15)
				(type solid)
			)
			(layer "F.Fab")
		)
		(fp_line
			(start -0.494 -0.25)
			(end 0.504 -0.25)
			(stroke
				(width 0.15)
				(type solid)
			)
			(layer "F.Fab")
		)
		(fp_line
			(start -0.494 0.248)
			(end -0.494 -0.25)
			(stroke
				(width 0.15)
				(type solid)
			)
			(layer "F.Fab")
		)
		(pad "1" smd roundrect
			(at -0.48 0 135)
			(size 0.59 0.64)
			(layers "F.Cu" "F.Mask" "F.Paste")
			(roundrect_rratio 0.25)
			(net 14 "/Deserializer/SIOB_P")
			(pintype "passive")
		)
		(pad "2" smd roundrect
			(at 0.48 0 135)
			(size 0.59 0.64)
			(layers "F.Cu" "F.Mask" "F.Paste")
			(roundrect_rratio 0.25)
			(net 115 "/Connectors/PoCB")
			(pintype "passive")
		)
	)
	(footprint "antmicro-footprints:C_0402_1005Metric"
		(layer "F.Cu")
		(at 131.064 75.946)
		(descr "Capacitor SMD 0402")
		(tags "capacitor SMD 0402")
		(property "Reference" "C15"
			(at 0.937 0.277 0)
			(layer "F.SilkS")
			(effects
				(font
					(size 0.7 0.7)
					(thickness 0.15)
				)
				(justify left bottom)
			)
		)
		(property "Value" "C_220p_0402"
			(at -1.022927 2.155213 0)
			(layer "F.Fab")
			(effects
				(font
					(size 0.7 0.7)
					(thickness 0.15)
				)
				(justify left bottom)
			)
		)
		(property "Datasheet" "https://spicat.kyocera-avx.com/product/mlcc/chartview/04025C221JAT2A/"
			(at 0 0 0)
			(layer "F.Fab")
			(hide yes)
			(effects
				(font
					(size 1.27 1.27)
					(thickness 0.15)
				)
			)
		)
		(property "Description" "SMD Multilayer Ceramic Capacitor, 220 pF, 50 V, 0402 [1005 Metric], ± 10%, X7R, MC"
			(at 0 0 0)
			(layer "F.Fab")
			(hide yes)
			(effects
				(font
					(size 1.27 1.27)
					(thickness 0.15)
				)
			)
		)
		(property "Author" "Antmicro"
			(at 0 0 0)
			(layer "F.Fab")
			(hide yes)
			(effects
				(font
					(size 1 1)
					(thickness 0.15)
				)
			)
		)
		(property "Dielectric" ""
			(at 0 0 0)
			(layer "F.Fab")
			(hide yes)
			(effects
				(font
					(size 1 1)
					(thickness 0.15)
				)
			)
		)
		(property "License" "Apache-2.0"
			(at 0 0 0)
			(layer "F.Fab")
			(hide yes)
			(effects
				(font
					(size 1 1)
					(thickness 0.15)
				)
			)
		)
		(property "MPN" "04025C221JAT2A"
			(at 0 0 0)
			(layer "F.Fab")
			(hide yes)
			(effects
				(font
					(size 1 1)
					(thickness 0.15)
				)
			)
		)
		(property "Manufacturer" "KYOCERA AVX"
			(at 0 0 0)
			(layer "F.Fab")
			(hide yes)
			(effects
				(font
					(size 1 1)
					(thickness 0.15)
				)
			)
		)
		(property "Val" "220p"
			(at 0 0 0)
			(layer "F.Fab")
			(hide yes)
			(effects
				(font
					(size 1 1)
					(thickness 0.15)
				)
			)
		)
		(property "Voltage" ""
			(at 0 0 0)
			(layer "F.Fab")
			(hide yes)
			(effects
				(font
					(size 1 1)
					(thickness 0.15)
				)
			)
		)
		(sheetname "/Power/")
		(sheetfile "power.kicad_sch")
		(attr smd)
		(fp_rect
			(start -0.925 -0.47)
			(end 0.925 0.47)
			(stroke
				(width 0.05)
				(type default)
			)
			(fill no)
			(layer "F.CrtYd")
		)
		(fp_line
			(start -0.494 -0.25)
			(end 0.504 -0.25)
			(stroke
				(width 0.15)
				(type solid)
			)
			(layer "F.Fab")
		)
		(fp_line
			(start -0.494 0.248)
			(end -0.494 -0.25)
			(stroke
				(width 0.15)
				(type solid)
			)
			(layer "F.Fab")
		)
		(fp_line
			(start 0.504 -0.25)
			(end 0.504 0.248)
			(stroke
				(width 0.15)
				(type solid)
			)
			(layer "F.Fab")
		)
		(fp_line
			(start 0.504 0.248)
			(end -0.494 0.248)
			(stroke
				(width 0.15)
				(type solid)
			)
			(layer "F.Fab")
		)
		(pad "1" smd roundrect
			(at -0.48 0)
			(size 0.59 0.64)
			(layers "F.Cu" "F.Mask" "F.Paste")
			(roundrect_rratio 0.25)
			(net 122 "/Power/FB_12V")
			(pintype "passive")
		)
		(pad "2" smd roundrect
			(at 0.48 0)
			(size 0.59 0.64)
			(layers "F.Cu" "F.Mask" "F.Paste")
			(roundrect_rratio 0.25)
			(net 123 "/Power/OUT_12V")
			(pintype "passive")
		)
	)
)
